# S9S_MB_2U (Grand Teton) — schematic netlist excerpt (pin names and nets, part order shuffled) for the footprints in the layout excerpt that follows; sources: Cadence DE-HDL packaged netlist, KiCad conversion of 03242023_DA0F0TMBIJ0_F0T_Motherboard_J_brd_V01_OCP.brd

R3242  Q_RES  2.2K 5% EMPTY  pkg 0402LF  page 241 : A = SMB_OCP_V3_2_3V3AUX_SCL ; B = P3V3_AUX
R4171  Q_RES  33.2 1% CHIP  pkg 0402LF  page 215 : A = GPU_3V3IO_RSVD3_ISO ; B = GPU_3V3IO_RSVD3_ISO_R
C816  Q_CAP_DIFFBUS  DIFF BUS_0.22UF 6.3V 20% X6S  pkg C0201  page 175 : \1\ = P5E_CPU1_PE1_TX_C_DN<10> ; \2\ = P5E_CPU1_PE1_TX_DN<10>

(kicad_pcb
	(version 20260206)
	(generator "pcbnew")
	(generator_version "10.0")
	(general
		(thickness 1.6)
		(legacy_teardrops no)
	)
	(paper "A4")
	(title_block
		(title "03242023_DA0F0TMBIJ0_F0T_Motherboard_J_brd_V01_OCP.brd")
		(comment 1 "Grand Teton / footprints 830-832 of 6105")
	)
	(layers
		(0 "F.Cu" signal "TOP")
		(4 "In1.Cu" signal "GND")
		(6 "In2.Cu" signal "IN1")
		(8 "In3.Cu" signal "GND1")
		(10 "In4.Cu" signal "IN2")
		(12 "In5.Cu" signal "GND2")
		(14 "In6.Cu" signal "IN3")
		(16 "In7.Cu" signal "GND3")
		(18 "In8.Cu" signal "VCC")
		(20 "In9.Cu" signal "VCC1")
		(22 "In10.Cu" signal "GND4")
		(24 "In11.Cu" signal "IN4")
		(26 "In12.Cu" signal "GND5")
		(28 "In13.Cu" signal "IN5")
		(30 "In14.Cu" signal "GND6")
		(32 "In15.Cu" signal "IN6")
		(34 "In16.Cu" signal "GND7")
		(2 "B.Cu" signal "BOTTOM")
		(9 "F.Adhes" user "F.Adhesive")
		(11 "B.Adhes" user "B.Adhesive")
		(13 "F.Paste" user "Package Geometry/Pastemask Top")
		(15 "B.Paste" user "Package Geometry/Pastemask Bottom")
		(5 "F.SilkS" user "Ref Des/Silkscreen Top")
		(7 "B.SilkS" user "Ref Des/Silkscreen Bottom")
		(1 "F.Mask" user "Board Geometry/Soldermask Top")
		(3 "B.Mask" user "Board Geometry/Soldermask Bottom")
		(17 "Dwgs.User" user "User.Drawings")
		(19 "Cmts.User" user "User.Comments")
		(21 "Eco1.User" user "User.Eco1")
		(23 "Eco2.User" user "User.Eco2")
		(25 "Edge.Cuts" user "Board Geometry/Outline")
		(27 "Margin" user)
		(31 "F.CrtYd" user "Package Geometry/Place Bound Top")
		(29 "B.CrtYd" user "Package Geometry/Place Bound Bottom")
		(35 "F.Fab" user "Ref Des/Assembly Top")
		(33 "B.Fab" user "Ref Des/Assembly Bottom")
	)
	(footprint ""
		(layer "F.Cu")
		(at 109.337856 -31.49981)
		(property "Reference" "R3242"
			(at 0 0 0)
			(layer "F.SilkS")
			(hide yes)
			(effects
				(font
					(size 1.27 1.27)
				)
			)
		)
		(property "Value" ""
			(at 0 0 0)
			(layer "F.Fab")
			(effects
				(font
					(size 1.27 1.27)
				)
			)
		)
		(duplicate_pad_numbers_are_jumpers no)
		(fp_line
			(start -0.7874 -0.4064)
			(end 0.7874 -0.4064)
			(stroke
				(width 0.1524)
				(type default)
			)
			(layer "F.SilkS")
		)
		(fp_line
			(start -0.7874 0.4064)
			(end -0.7874 -0.4064)
			(stroke
				(width 0.1524)
				(type default)
			)
			(layer "F.SilkS")
		)
		(fp_line
			(start 0.7874 -0.4064)
			(end 0.7874 0.4064)
			(stroke
				(width 0.1524)
				(type default)
			)
			(layer "F.SilkS")
		)
		(fp_line
			(start 0.7874 0.4064)
			(end -0.7874 0.4064)
			(stroke
				(width 0.1524)
				(type default)
			)
			(layer "F.SilkS")
		)
		(fp_line
			(start -0.67945 -0.305054)
			(end -0.12065 -0.305054)
			(stroke
				(width 0.1)
				(type default)
			)
			(layer "F.Fab")
		)
		(fp_line
			(start -0.67945 0.3048)
			(end -0.67945 -0.305054)
			(stroke
				(width 0.1)
				(type default)
			)
			(layer "F.Fab")
		)
		(fp_line
			(start -0.12065 -0.305054)
			(end -0.12065 -0.2794)
			(stroke
				(width 0.1)
				(type default)
			)
			(layer "F.Fab")
		)
		(fp_line
			(start -0.12065 -0.2794)
			(end 0.12065 -0.2794)
			(stroke
				(width 0.1)
				(type default)
			)
			(layer "F.Fab")
		)
		(fp_line
			(start -0.12065 0.2794)
			(end -0.12065 0.3048)
			(stroke
				(width 0.1)
				(type default)
			)
			(layer "F.Fab")
		)
		(fp_line
			(start -0.12065 0.3048)
			(end -0.67945 0.3048)
			(stroke
				(width 0.1)
				(type default)
			)
			(layer "F.Fab")
		)
		(fp_line
			(start 0.120396 0.2794)
			(end -0.12065 0.2794)
			(stroke
				(width 0.1)
				(type default)
			)
			(layer "F.Fab")
		)
		(fp_line
			(start 0.120396 0.3048)
			(end 0.120396 0.2794)
			(stroke
				(width 0.1)
				(type default)
			)
			(layer "F.Fab")
		)
		(fp_line
			(start 0.12065 -0.3048)
			(end 0.67945 -0.3048)
			(stroke
				(width 0.1)
				(type default)
			)
			(layer "F.Fab")
		)
		(fp_line
			(start 0.12065 -0.2794)
			(end 0.12065 -0.3048)
			(stroke
				(width 0.1)
				(type default)
			)
			(layer "F.Fab")
		)
		(fp_line
			(start 0.67945 -0.3048)
			(end 0.67945 0.3048)
			(stroke
				(width 0.1)
				(type default)
			)
			(layer "F.Fab")
		)
		(fp_line
			(start 0.67945 0.3048)
			(end 0.120396 0.3048)
			(stroke
				(width 0.1)
				(type default)
			)
			(layer "F.Fab")
		)
		(pad "1" smd circle
			(at -0.40005 0)
			(size 0 0)
			(layers "F.Cu" "F.Mask" "F.Paste")
			(net "SMB_OCP_V3_2_3V3AUX_SCL")
		)
		(pad "2" smd circle
			(at 0.40005 0)
			(size 0 0)
			(layers "F.Cu" "F.Mask" "F.Paste")
			(net "P3V3_AUX")
		)
	)
	(footprint ""
		(layer "F.Cu")
		(at 204.93736 -118.074948 180)
		(property "Reference" "R4171"
			(at 0 0 180)
			(layer "F.SilkS")
			(hide yes)
			(effects
				(font
					(size 1.27 1.27)
				)
			)
		)
		(property "Value" ""
			(at 0 0 180)
			(layer "F.Fab")
			(effects
				(font
					(size 1.27 1.27)
				)
			)
		)
		(duplicate_pad_numbers_are_jumpers no)
		(fp_line
			(start 0.7874 0.4064)
			(end -0.7874 0.4064)
			(stroke
				(width 0.1524)
				(type default)
			)
			(layer "F.SilkS")
		)
		(fp_line
			(start 0.7874 -0.4064)
			(end 0.7874 0.4064)
			(stroke
				(width 0.1524)
				(type default)
			)
			(layer "F.SilkS")
		)
		(fp_line
			(start -0.7874 0.4064)
			(end -0.7874 -0.4064)
			(stroke
				(width 0.1524)
				(type default)
			)
			(layer "F.SilkS")
		)
		(fp_line
			(start -0.7874 -0.4064)
			(end 0.7874 -0.4064)
			(stroke
				(width 0.1524)
				(type default)
			)
			(layer "F.SilkS")
		)
		(fp_line
			(start 0.67945 0.3048)
			(end 0.120396 0.3048)
			(stroke
				(width 0.1)
				(type default)
			)
			(layer "F.Fab")
		)
		(fp_line
			(start 0.67945 -0.3048)
			(end 0.67945 0.3048)
			(stroke
				(width 0.1)
				(type default)
			)
			(layer "F.Fab")
		)
		(fp_line
			(start 0.12065 -0.2794)
			(end 0.12065 -0.3048)
			(stroke
				(width 0.1)
				(type default)
			)
			(layer "F.Fab")
		)
		(fp_line
			(start 0.12065 -0.3048)
			(end 0.67945 -0.3048)
			(stroke
				(width 0.1)
				(type default)
			)
			(layer "F.Fab")
		)
		(fp_line
			(start 0.120396 0.3048)
			(end 0.120396 0.2794)
			(stroke
				(width 0.1)
				(type default)
			)
			(layer "F.Fab")
		)
		(fp_line
			(start 0.120396 0.2794)
			(end -0.12065 0.2794)
			(stroke
				(width 0.1)
				(type default)
			)
			(layer "F.Fab")
		)
		(fp_line
			(start -0.12065 0.3048)
			(end -0.67945 0.3048)
			(stroke
				(width 0.1)
				(type default)
			)
			(layer "F.Fab")
		)
		(fp_line
			(start -0.12065 0.2794)
			(end -0.12065 0.3048)
			(stroke
				(width 0.1)
				(type default)
			)
			(layer "F.Fab")
		)
		(fp_line
			(start -0.12065 -0.2794)
			(end 0.12065 -0.2794)
			(stroke
				(width 0.1)
				(type default)
			)
			(layer "F.Fab")
		)
		(fp_line
			(start -0.12065 -0.305054)
			(end -0.12065 -0.2794)
			(stroke
				(width 0.1)
				(type default)
			)
			(layer "F.Fab")
		)
		(fp_line
			(start -0.67945 0.3048)
			(end -0.67945 -0.305054)
			(stroke
				(width 0.1)
				(type default)
			)
			(layer "F.Fab")
		)
		(fp_line
			(start -0.67945 -0.305054)
			(end -0.12065 -0.305054)
			(stroke
				(width 0.1)
				(type default)
			)
			(layer "F.Fab")
		)
		(pad "1" smd circle
			(at -0.40005 0 180)
			(size 0 0)
			(layers "F.Cu" "F.Mask" "F.Paste")
			(net "GPU_3V3IO_RSVD3_ISO")
		)
		(pad "2" smd circle
			(at 0.40005 0 180)
			(size 0 0)
			(layers "F.Cu" "F.Mask" "F.Paste")
			(net "GPU_3V3IO_RSVD3_ISO_R")
		)
	)
	(footprint ""
		(layer "F.Cu")
		(at 29.478478 -17.623536 90)
		(property "Reference" "C816"
			(at 0 0 90)
			(layer "F.SilkS")
			(hide yes)
			(effects
				(font
					(size 1.27 1.27)
				)
			)
		)
		(property "Value" ""
			(at 0 0 90)
			(layer "F.Fab")
			(effects
				(font
					(size 1.27 1.27)
				)
			)
		)
		(duplicate_pad_numbers_are_jumpers no)
		(fp_line
			(start 0.299974 -0.150114)
			(end 0.299974 0.150114)
			(stroke
				(width 0.1)
				(type default)
			)
			(layer "F.Fab")
		)
		(fp_line
			(start -0.299974 -0.150114)
			(end 0.299974 -0.150114)
			(stroke
				(width 0.1)
				(type default)
			)
			(layer "F.Fab")
		)
		(fp_line
			(start 0.299974 0.150114)
			(end -0.299974 0.150114)
			(stroke
				(width 0.1)
				(type default)
			)
			(layer "F.Fab")
		)
		(fp_line
			(start -0.299974 0.150114)
			(end -0.299974 -0.150114)
			(stroke
				(width 0.1)
				(type default)
			)
			(layer "F.Fab")
		)
		(pad "1" smd rect
			(at -0.2667 0 90)
			(size 0.3048 0.381)
			(layers "F.Cu" "F.Mask" "F.Paste")
			(net "P5E_CPU1_PE1_TX_C_DN<10>")
		)
		(pad "2" smd rect
			(at 0.2667 0 90)
			(size 0.3048 0.381)
			(layers "F.Cu" "F.Mask" "F.Paste")
			(net "P5E_CPU1_PE1_TX_DN<10>")
		)
	)
)
